FILE_TYPE = MACRO_DRAWING;
SET COLOR_WIRE YELLOW;
SET COLOR_PROP ORANGE;
SET COLOR_DOT WHITE;
SET COLOR_ARC YELLOW;
SET COLOR_BODY GREEN;
SET COLOR_NOTE PURPLE;
SET PROP_DISPLAY VALUE;
SET PAGE_NUMBER P413;
FORCEADD QUANTA_TITLE_BLOCK_C..1
(0 0);
FORCEPROP 1 LAST CUSTOM_TXT_CDS <NAME_2>
J 0
(-3175 50);
FORCEPROP 1 LAST CUSTOM_TXT_CDS <NAME_1>
J 0
(-3175 175);
FORCEPROP 1 LAST CUSTOM_TXT_CDS <Q_NUMBER>
J 0
(-1403 103);
DISPLAY 1.212766 (-1403 103);
FORCEPROP 1 LAST CUSTOM_TXT_CDS <Q_PROJ>
J 0
(-2382 102);
DISPLAY 1.212766 (-2382 102);
FORCEPROP 1 LAST CUSTOM_TXT_CDS <Q_REV>
J 0
(-184 103);
DISPLAY 1.212766 (-184 103);
FORCEPROP 1 LAST CUSTOM_TXT_CDS <CON_LAST_MODIFIED>
J 0
(-1885 15);
DISPLAY 0.978723 (-1885 15);
FORCEPROP 1 LAST CUSTOM_TXT_CDS <CON_PAGE_NUM> OF <CON_TOTAL_PAGES>
J 0
(-446 18);
DISPLAY 0.978723 (-446 18);
FORCEPROP 1 LAST Q_TITLE RETIMER_CPU0_P1(10)
J 0
(-9366 26);
DISPLAY 2.446809 (-9366 26);
PAINT GREEN (-9366 26);
FORCEPROP 2 LAST CDS_LIB pure_quanta
J 0
(0 0);
DISPLAY INVISIBLE (0 0);
FORCEPROP 1 LAST CDS_LMAN_SYM_OUTLINE -9475,6775,100,-125
J 0
(0 0);
DISPLAY 0.468085 (0 0);
PAINT GREEN (0 0);
DISPLAY INVISIBLE (0 0);
FORCEPROP 2 LAST PAGE_BORDER TRUE
J 0
(-7890 5250);
DISPLAY 0.638298 (-7890 5250);
PAINT PINK (-7890 5250);
DISPLAY INVISIBLE (-7890 5250);
FORCEPROP 2 LAST CDS_XR_PAGE_TITLE CR-293 : @T6G_MB_LIB.T6G(SCH_1):PAGE293
J 0
(-7890 5250);
DISPLAY 0.638298 (-7890 5250);
PAINT PINK (-7890 5250);
DISPLAY INVISIBLE (-7890 5250);
FORCEPROP 2 LAST CUSTOM_TXT_CDS <XR_PAGE_TITLE>
J 0
(-7890 5250);
DISPLAY 0.638298 (-7890 5250);
PAINT PINK (-7890 5250);
DISPLAY INVISIBLE (-7890 5250);
FORCEPROP 1 LAST COMMENT_BODY TRUE
J 0
(12 -13);
DISPLAY 0.978723 (12 -13);
PAINT GREEN (12 -13);
DISPLAY INVISIBLE (12 -13);
FORCEPROP 1 LAST Q_DEPT BU9
J 1
(-3763 49);
DISPLAY 1.957447 (-3763 49);
PAINT GREEN (-3763 49);
DISPLAY INVISIBLE (-3763 49);
FORCEPROP 0 LAST CDS_CON_LAST_MODIFIED Thu Aug 24 10:16:18 2023
J 0
(-1885 15);
DISPLAY INVISIBLE (-1885 15);
QUIT
